(kicad_pcb
	(version 20241229)
	(generator "pcbnew")
	(generator_version "9.0")
	(general
		(thickness 1.62)
		(legacy_teardrops no)
	)
	(paper "A4")
	(title_block
		(title "OCuLink to 10GbE adapter")
		(date "2026-02-23")
		(rev "1.1.0")
		(company "Antmicro Ltd")
		(comment 1 "www.antmicro.com")
		(comment 9 "footprints 107-112 of 510")
	)
	(layers
		(0 "F.Cu" signal)
		(4 "In1.Cu" signal)
		(6 "In2.Cu" signal)
		(8 "In3.Cu" signal)
		(10 "In4.Cu" signal)
		(12 "In5.Cu" signal)
		(14 "In6.Cu" signal)
		(2 "B.Cu" signal)
		(9 "F.Adhes" user "F.Adhesive")
		(11 "B.Adhes" user "B.Adhesive")
		(13 "F.Paste" user)
		(15 "B.Paste" user)
		(5 "F.SilkS" user "F.Silkscreen")
		(7 "B.SilkS" user "B.Silkscreen")
		(1 "F.Mask" user)
		(3 "B.Mask" user)
		(17 "Dwgs.User" user "User.Drawings")
		(19 "Cmts.User" user "User.Comments")
		(21 "Eco1.User" user "User.Eco1")
		(23 "Eco2.User" user "User.Eco2")
		(25 "Edge.Cuts" user)
		(27 "Margin" user)
		(31 "F.CrtYd" user "F.Courtyard")
		(29 "B.CrtYd" user "B.Courtyard")
		(35 "F.Fab" user)
		(33 "B.Fab" user)
	)
	(footprint "antmicro-footprints:C_0402_1005Metric"
		(layer "F.Cu")
		(at 67.27 114.3 180)
		(descr "Capacitor SMD 0402")
		(tags "capacitor SMD 0402")
		(property "Reference" "C171"
			(at 0.69 0.36 0)
			(layer "F.SilkS")
			(effects
				(font
					(size 0.7 0.7)
					(thickness 0.15)
				)
				(justify right top)
			)
		)
		(property "Value" "C_100n_0402"
			(at -1.022927 2.155213 0)
			(layer "F.Fab")
			(hide yes)
			(effects
				(font
					(size 0.7 0.7)
					(thickness 0.15)
				)
				(justify right top)
			)
		)
		(property "Datasheet" "https://www.murata.com/products/productdetail?partno=GRM155R61H104KE14%23"
			(at 0 0 0)
			(layer "F.Fab")
			(hide yes)
			(effects
				(font
					(size 1.27 1.27)
					(thickness 0.15)
				)
			)
		)
		(property "Description" "SMD Multilayer Ceramic Capacitor, 0.1 µF, 50 V, 0402 [1005 Metric], ± 10%, X5R, GRM Series"
			(at 0 0 0)
			(layer "F.Fab")
			(hide yes)
			(effects
				(font
					(size 1.27 1.27)
					(thickness 0.15)
				)
			)
		)
		(property "MPN" "GRM155R61H104KE14D"
			(at 0 0 180)
			(unlocked yes)
			(layer "F.Fab")
			(hide yes)
			(effects
				(font
					(size 1 1)
					(thickness 0.15)
				)
			)
		)
		(property "Val" "100n"
			(at 0 0 180)
			(unlocked yes)
			(layer "F.Fab")
			(hide yes)
			(effects
				(font
					(size 1 1)
					(thickness 0.15)
				)
			)
		)
		(property "Voltage" "50V"
			(at 0 0 180)
			(unlocked yes)
			(layer "F.Fab")
			(hide yes)
			(effects
				(font
					(size 1 1)
					(thickness 0.15)
				)
			)
		)
		(property "Dielectric" "X5R"
			(at 0 0 180)
			(unlocked yes)
			(layer "F.Fab")
			(hide yes)
			(effects
				(font
					(size 1 1)
					(thickness 0.15)
				)
			)
		)
		(property "Manufacturer" "Murata"
			(at 0 0 180)
			(unlocked yes)
			(layer "F.Fab")
			(hide yes)
			(effects
				(font
					(size 1 1)
					(thickness 0.15)
				)
			)
		)
		(property "License" "Apache-2.0"
			(at 0 0 180)
			(unlocked yes)
			(layer "F.Fab")
			(hide yes)
			(effects
				(font
					(size 1 1)
					(thickness 0.15)
				)
			)
		)
		(property "Author" "Antmicro"
			(at 0 0 180)
			(unlocked yes)
			(layer "F.Fab")
			(hide yes)
			(effects
				(font
					(size 1 1)
					(thickness 0.15)
				)
			)
		)
		(sheetname "/X710-AT2 power/")
		(sheetfile "x710-at2-power.kicad_sch")
		(attr smd)
		(fp_rect
			(start -0.925 -0.47)
			(end 0.925 0.47)
			(stroke
				(width 0.05)
				(type default)
			)
			(fill no)
			(layer "F.CrtYd")
		)
		(fp_line
			(start 0.504 0.248)
			(end -0.494 0.248)
			(stroke
				(width 0.15)
				(type solid)
			)
			(layer "F.Fab")
		)
		(fp_line
			(start 0.504 -0.25)
			(end 0.504 0.248)
			(stroke
				(width 0.15)
				(type solid)
			)
			(layer "F.Fab")
		)
		(fp_line
			(start -0.494 0.248)
			(end -0.494 -0.25)
			(stroke
				(width 0.15)
				(type solid)
			)
			(layer "F.Fab")
		)
		(fp_line
			(start -0.494 -0.25)
			(end 0.504 -0.25)
			(stroke
				(width 0.15)
				(type solid)
			)
			(layer "F.Fab")
		)
		(pad "1" smd roundrect
			(at -0.48 0 180)
			(size 0.59 0.64)
			(layers "F.Cu" "F.Mask" "F.Paste")
			(roundrect_rratio 0.25)
			(net 28 "GND")
			(pintype "passive")
		)
		(pad "2" smd roundrect
			(at 0.48 0 180)
			(size 0.59 0.64)
			(layers "F.Cu" "F.Mask" "F.Paste")
			(roundrect_rratio 0.25)
			(net 302 "+1V0")
			(pintype "passive")
		)
	)
	(footprint "antmicro-footprints:R_0402_1005Metric"
		(layer "F.Cu")
		(at 80.35 84.15)
		(descr "Resistor SMD 0402")
		(tags "resistor SMD 0402")
		(property "Reference" "R103"
			(at 1.05 -1.5 0)
			(layer "F.SilkS")
			(effects
				(font
					(size 0.7 0.7)
					(thickness 0.15)
				)
				(justify right bottom)
			)
		)
		(property "Value" "R_3k3_0402"
			(at -1.011843 1.772046 0)
			(layer "F.Fab")
			(hide yes)
			(effects
				(font
					(size 0.7 0.7)
					(thickness 0.15)
				)
				(justify left bottom)
			)
		)
		(property "Datasheet" "https://www.bourns.com/docs/product-datasheets/cr.pdf"
			(at 0 0 0)
			(layer "F.Fab")
			(hide yes)
			(effects
				(font
					(size 1.27 1.27)
					(thickness 0.15)
				)
			)
		)
		(property "Description" "SMD Chip Resistor, 3.3 kohm, ± 1%, 63 mW, 0402 [1005 Metric], Thick Film, General Purpose"
			(at 0 0 0)
			(layer "F.Fab")
			(hide yes)
			(effects
				(font
					(size 1.27 1.27)
					(thickness 0.15)
				)
			)
		)
		(property "MPN" "CR0402-FX-3301GLF"
			(at 0 0 0)
			(unlocked yes)
			(layer "F.Fab")
			(hide yes)
			(effects
				(font
					(size 1 1)
					(thickness 0.15)
				)
			)
		)
		(property "Manufacturer" "Bourns"
			(at 0 0 0)
			(unlocked yes)
			(layer "F.Fab")
			(hide yes)
			(effects
				(font
					(size 1 1)
					(thickness 0.15)
				)
			)
		)
		(property "License" "Apache-2.0"
			(at 0 0 0)
			(unlocked yes)
			(layer "F.Fab")
			(hide yes)
			(effects
				(font
					(size 1 1)
					(thickness 0.15)
				)
			)
		)
		(property "Author" "Antmicro"
			(at 0 0 0)
			(unlocked yes)
			(layer "F.Fab")
			(hide yes)
			(effects
				(font
					(size 1 1)
					(thickness 0.15)
				)
			)
		)
		(property "Val" "3k3"
			(at 0 0 0)
			(unlocked yes)
			(layer "F.Fab")
			(hide yes)
			(effects
				(font
					(size 1 1)
					(thickness 0.15)
				)
			)
		)
		(property "Tolerance" "1%"
			(at 0 0 0)
			(unlocked yes)
			(layer "F.Fab")
			(hide yes)
			(effects
				(font
					(size 1 1)
					(thickness 0.15)
				)
			)
		)
		(sheetname "/X710-AT2 Misc/")
		(sheetfile "x710-at2-mics.kicad_sch")
		(attr smd)
		(fp_rect
			(start -0.925 -0.47)
			(end 0.925 0.47)
			(stroke
				(width 0.05)
				(type default)
			)
			(fill no)
			(layer "F.CrtYd")
		)
		(fp_rect
			(start -0.5 -0.25)
			(end 0.5 0.25)
			(stroke
				(width 0.15)
				(type solid)
			)
			(fill no)
			(layer "F.Fab")
		)
		(pad "1" smd roundrect
			(at -0.48 0)
			(size 0.59 0.64)
			(layers "F.Cu" "F.Mask" "F.Paste")
			(roundrect_rratio 0.25)
			(net 99 "/X710-AT2 Misc/LAN_PWR_GOOD")
			(pintype "passive")
		)
		(pad "2" smd roundrect
			(at 0.48 0)
			(size 0.59 0.64)
			(layers "F.Cu" "F.Mask" "F.Paste")
			(roundrect_rratio 0.25)
			(net 78 "Net-(U10-VCC)")
			(pintype "passive")
		)
	)
	(footprint "antmicro-footprints:L_Bourns-SRP4021HMT"
		(layer "F.Cu")
		(at 99.55 94.4 180)
		(property "Reference" "L8"
			(at -2.2 2.2 0)
			(layer "F.SilkS")
			(effects
				(font
					(size 0.7 0.7)
					(thickness 0.15)
				)
				(justify right bottom)
			)
		)
		(property "Value" "L_1u_10A_Bourns-SRP4021HMT"
			(at -2.85 3.4 0)
			(layer "F.Fab")
			(hide yes)
			(effects
				(font
					(size 0.7 0.7)
					(thickness 0.15)
				)
				(justify right top)
			)
		)
		(property "Datasheet" "https://www.mouser.com/datasheet/2/54/Bourns_04_01_2025_SRP4021HMT_Datasheet-3580094.pdf"
			(at 0 0 0)
			(layer "F.Fab")
			(hide yes)
			(effects
				(font
					(size 0.7 0.7)
					(thickness 0.15)
				)
				(justify right top)
			)
		)
		(property "Description" "Power Inductors - SMD Ind,4.1x4.2x1.9mm,1uH+/-20%,10A, Shielded"
			(at 0 0 0)
			(layer "F.Fab")
			(hide yes)
			(effects
				(font
					(size 0.7 0.7)
					(thickness 0.15)
				)
				(justify right top)
			)
		)
		(property "Val" "1u/10A"
			(at 0 0 180)
			(unlocked yes)
			(layer "F.Fab")
			(hide yes)
			(effects
				(font
					(size 1 1)
					(thickness 0.15)
				)
			)
		)
		(property "Manufacturer" "Bourns"
			(at 0 0 180)
			(unlocked yes)
			(layer "F.Fab")
			(hide yes)
			(effects
				(font
					(size 1 1)
					(thickness 0.15)
				)
			)
		)
		(property "MPN" "SRP4021HMT-1R0M"
			(at 0 0 180)
			(unlocked yes)
			(layer "F.Fab")
			(hide yes)
			(effects
				(font
					(size 1 1)
					(thickness 0.15)
				)
			)
		)
		(property "ISat" ""
			(at 0 0 180)
			(unlocked yes)
			(layer "F.Fab")
			(hide yes)
			(effects
				(font
					(size 1 1)
					(thickness 0.15)
				)
			)
		)
		(property "Isat" "8A"
			(at 0 0 180)
			(unlocked yes)
			(layer "F.Fab")
			(hide yes)
			(effects
				(font
					(size 1 1)
					(thickness 0.15)
				)
			)
		)
		(property "IMax" ""
			(at 0 0 180)
			(unlocked yes)
			(layer "F.Fab")
			(hide yes)
			(effects
				(font
					(size 1 1)
					(thickness 0.15)
				)
			)
		)
		(property "Imax" "10A"
			(at 0 0 180)
			(unlocked yes)
			(layer "F.Fab")
			(hide yes)
			(effects
				(font
					(size 1 1)
					(thickness 0.15)
				)
			)
		)
		(property "Size" "4.2x4.1"
			(at 0 0 180)
			(unlocked yes)
			(layer "F.Fab")
			(hide yes)
			(effects
				(font
					(size 1 1)
					(thickness 0.15)
				)
			)
		)
		(property "Author" "Antmicro"
			(at 0 0 180)
			(unlocked yes)
			(layer "F.Fab")
			(hide yes)
			(effects
				(font
					(size 1 1)
					(thickness 0.15)
				)
			)
		)
		(property "License" "Apache-2.0"
			(at 0 0 180)
			(unlocked yes)
			(layer "F.Fab")
			(hide yes)
			(effects
				(font
					(size 1 1)
					(thickness 0.15)
				)
			)
		)
		(sheetname "/X710-AT2 power/")
		(sheetfile "x710-at2-power.kicad_sch")
		(attr smd)
		(fp_line
			(start -0.8 2.05)
			(end 0.8 2.05)
			(stroke
				(width 0.15)
				(type solid)
			)
			(layer "F.SilkS")
		)
		(fp_line
			(start -0.8 -2.05)
			(end 0.8 -2.05)
			(stroke
				(width 0.15)
				(type solid)
			)
			(layer "F.SilkS")
		)
		(fp_rect
			(start -2.85 -2.3)
			(end 2.85 2.3)
			(stroke
				(width 0.05)
				(type solid)
			)
			(fill no)
			(layer "F.CrtYd")
		)
		(fp_rect
			(start -2 -2.05)
			(end 2 2.05)
			(stroke
				(width 0.15)
				(type solid)
			)
			(fill no)
			(layer "F.Fab")
		)
		(pad "1" smd rect
			(at 1.85 0)
			(size 1.5 3.5)
			(layers "F.Cu" "F.Mask" "F.Paste")
			(net 155 "Net-(U9H-SVR_IND)")
			(pintype "passive")
		)
		(pad "2" smd rect
			(at -1.85 0)
			(size 1.5 3.5)
			(layers "F.Cu" "F.Mask" "F.Paste")
			(net 1 "VCCA")
			(pintype "passive")
		)
	)
	(footprint "antmicro-footprints:R_0402_1005Metric"
		(layer "F.Cu")
		(at 101.3 105.2)
		(descr "Resistor SMD 0402")
		(tags "resistor SMD 0402")
		(property "Reference" "R90"
			(at -0.8 15.3 0)
			(layer "F.SilkS")
			(effects
				(font
					(size 0.7 0.7)
					(thickness 0.15)
				)
				(justify left bottom)
			)
		)
		(property "Value" "R_10k_0402"
			(at -1.011843 1.772046 0)
			(layer "F.Fab")
			(hide yes)
			(effects
				(font
					(size 0.7 0.7)
					(thickness 0.15)
				)
				(justify left bottom)
			)
		)
		(property "Datasheet" "https://www.bourns.com/docs/product-datasheets/cr.pdf"
			(at 0 0 0)
			(layer "F.Fab")
			(hide yes)
			(effects
				(font
					(size 1.27 1.27)
					(thickness 0.15)
				)
			)
		)
		(property "Description" "SMD Chip Resistor, 10 kohm, ± 1%, 62.5 mW, 0402 [1005 Metric], Thick Film, General Purpose"
			(at 0 0 0)
			(layer "F.Fab")
			(hide yes)
			(effects
				(font
					(size 1.27 1.27)
					(thickness 0.15)
				)
			)
		)
		(property "MPN" "CR0402-FX-1002GLF"
			(at 0 0 0)
			(unlocked yes)
			(layer "F.Fab")
			(hide yes)
			(effects
				(font
					(size 1 1)
					(thickness 0.15)
				)
			)
		)
		(property "Manufacturer" "Bourns"
			(at 0 0 0)
			(unlocked yes)
			(layer "F.Fab")
			(hide yes)
			(effects
				(font
					(size 1 1)
					(thickness 0.15)
				)
			)
		)
		(property "License" "Apache-2.0"
			(at 0 0 0)
			(unlocked yes)
			(layer "F.Fab")
			(hide yes)
			(effects
				(font
					(size 1 1)
					(thickness 0.15)
				)
			)
		)
		(property "Author" "Antmicro"
			(at 0 0 0)
			(unlocked yes)
			(layer "F.Fab")
			(hide yes)
			(effects
				(font
					(size 1 1)
					(thickness 0.15)
				)
			)
		)
		(property "Val" "10k"
			(at 0 0 0)
			(unlocked yes)
			(layer "F.Fab")
			(hide yes)
			(effects
				(font
					(size 1 1)
					(thickness 0.15)
				)
			)
		)
		(property "Tolerance" "1%"
			(at 0 0 0)
			(unlocked yes)
			(layer "F.Fab")
			(hide yes)
			(effects
				(font
					(size 1 1)
					(thickness 0.15)
				)
			)
		)
		(sheetname "/X710-AT2 Misc/")
		(sheetfile "x710-at2-mics.kicad_sch")
		(attr smd)
		(fp_rect
			(start -0.925 -0.47)
			(end 0.925 0.47)
			(stroke
				(width 0.05)
				(type default)
			)
			(fill no)
			(layer "F.CrtYd")
		)
		(fp_rect
			(start -0.5 -0.25)
			(end 0.5 0.25)
			(stroke
				(width 0.15)
				(type solid)
			)
			(fill no)
			(layer "F.Fab")
		)
		(pad "1" smd roundrect
			(at -0.48 0)
			(size 0.59 0.64)
			(layers "F.Cu" "F.Mask" "F.Paste")
			(roundrect_rratio 0.25)
			(net 28 "GND")
			(pintype "passive")
		)
		(pad "2" smd roundrect
			(at 0.48 0)
			(size 0.59 0.64)
			(layers "F.Cu" "F.Mask" "F.Paste")
			(roundrect_rratio 0.25)
			(net 368 "/X710-AT2 Misc/NCSI.ARB_IN")
			(pintype "passive")
		)
	)
	(footprint "antmicro-footprints:C_0603_1608Metric_EIA"
		(layer "F.Cu")
		(at 67.25 111.55 180)
		(descr "Capacitor SMD 0603, IPC-7351 Density Level A")
		(tags "Capacitor 0603")
		(property "Reference" "C161"
			(at 0.94 0.17 0)
			(layer "F.SilkS")
			(effects
				(font
					(size 0.7 0.7)
					(thickness 0.15)
				)
				(justify right top)
			)
		)
		(property "Value" "C_22u_16V_0603"
			(at -1.42757 1.770288 0)
			(layer "F.Fab")
			(hide yes)
			(effects
				(font
					(size 0.7 0.7)
					(thickness 0.15)
				)
				(justify right top)
			)
		)
		(property "Datasheet" "https://product.samsungsem.com/mlcc/CL10A226MO7JZN.do"
			(at 0 0 0)
			(layer "F.Fab")
			(hide yes)
			(effects
				(font
					(size 1.27 1.27)
					(thickness 0.15)
				)
			)
		)
		(property "Description" "SMD Multilayer Ceramic Capacitor"
			(at 0 0 0)
			(layer "F.Fab")
			(hide yes)
			(effects
				(font
					(size 1.27 1.27)
					(thickness 0.15)
				)
			)
		)
		(property "MPN" "CL10A226MO7JZNC"
			(at 0 0 180)
			(unlocked yes)
			(layer "F.Fab")
			(hide yes)
			(effects
				(font
					(size 1 1)
					(thickness 0.15)
				)
			)
		)
		(property "Manufacturer" "Samsung Electro-Mechanics"
			(at 0 0 180)
			(unlocked yes)
			(layer "F.Fab")
			(hide yes)
			(effects
				(font
					(size 1 1)
					(thickness 0.15)
				)
			)
		)
		(property "License" "Apache-2.0"
			(at 0 0 180)
			(unlocked yes)
			(layer "F.Fab")
			(hide yes)
			(effects
				(font
					(size 1 1)
					(thickness 0.15)
				)
			)
		)
		(property "Author" "Antmicro"
			(at 0 0 180)
			(unlocked yes)
			(layer "F.Fab")
			(hide yes)
			(effects
				(font
					(size 1 1)
					(thickness 0.15)
				)
			)
		)
		(property "Val" "22u"
			(at 0 0 180)
			(unlocked yes)
			(layer "F.Fab")
			(hide yes)
			(effects
				(font
					(size 1 1)
					(thickness 0.15)
				)
			)
		)
		(property "Voltage" "16V"
			(at 0 0 180)
			(unlocked yes)
			(layer "F.Fab")
			(hide yes)
			(effects
				(font
					(size 1 1)
					(thickness 0.15)
				)
			)
		)
		(property "Dielectric" ""
			(at 0 0 180)
			(unlocked yes)
			(layer "F.Fab")
			(hide yes)
			(effects
				(font
					(size 1 1)
					(thickness 0.15)
				)
			)
		)
		(sheetname "/X710-AT2 power/")
		(sheetfile "x710-at2-power.kicad_sch")
		(attr smd)
		(fp_line
			(start -0.15 0.55)
			(end 0.15 0.55)
			(stroke
				(width 0.15)
				(type solid)
			)
			(layer "F.SilkS")
		)
		(fp_line
			(start -0.15 -0.55)
			(end 0.15 -0.55)
			(stroke
				(width 0.15)
				(type solid)
			)
			(layer "F.SilkS")
		)
		(fp_rect
			(start -1.25 -0.65)
			(end 1.25 0.65)
			(stroke
				(width 0.05)
				(type solid)
			)
			(fill no)
			(layer "F.CrtYd")
		)
		(fp_rect
			(start -0.8 -0.45)
			(end 0.8 0.45)
			(stroke
				(width 0.15)
				(type solid)
			)
			(fill no)
			(layer "F.Fab")
		)
		(pad "1" smd roundrect
			(at -0.7 0 180)
			(size 0.8 1.1)
			(layers "F.Cu" "F.Mask" "F.Paste")
			(roundrect_rratio 0.2)
			(net 28 "GND")
			(pintype "passive")
		)
		(pad "2" smd roundrect
			(at 0.7 0 180)
			(size 0.8 1.1)
			(layers "F.Cu" "F.Mask" "F.Paste")
			(roundrect_rratio 0.2)
			(net 302 "+1V0")
			(pintype "passive")
		)
	)
	(footprint "antmicro-footprints:R_0603_1608Metric"
		(layer "F.Cu")
		(at 63.2 84.1)
		(descr "Resistor SMD 0603")
		(tags "resistor SMD 0603")
		(property "Reference" "R8"
			(at -1.26 -1.54 0)
			(layer "F.SilkS")
			(effects
				(font
					(size 0.7 0.7)
					(thickness 0.15)
				)
				(justify left bottom)
			)
		)
		(property "Value" "R_0R_22.4A_0603"
			(at 0 1.6 0)
			(layer "F.Fab")
			(hide yes)
			(effects
				(font
					(size 0.7 0.7)
					(thickness 0.15)
				)
				(justify left bottom)
			)
		)
		(property "Datasheet" "https://fscdn.rohm.com/en/products/databook/datasheet/passive/resistor/chip_resistor/pmr-jpw-e.pdf"
			(at 0 0 0)
			(layer "F.Fab")
			(hide yes)
			(effects
				(font
					(size 1.27 1.27)
					(thickness 0.15)
				)
			)
		)
		(property "Description" "SMD Chip Resistor"
			(at 0 0 0)
			(layer "F.Fab")
			(hide yes)
			(effects
				(font
					(size 1.27 1.27)
					(thickness 0.15)
				)
			)
		)
		(property "MPN" "PMR03EZPJ000"
			(at 0 0 0)
			(unlocked yes)
			(layer "F.Fab")
			(hide yes)
			(effects
				(font
					(size 1 1)
					(thickness 0.15)
				)
			)
		)
		(property "Manufacturer" "ROHM Semiconductor"
			(at 0 0 0)
			(unlocked yes)
			(layer "F.Fab")
			(hide yes)
			(effects
				(font
					(size 1 1)
					(thickness 0.15)
				)
			)
		)
		(property "Val" "0R"
			(at 0 0 0)
			(unlocked yes)
			(layer "F.Fab")
			(hide yes)
			(effects
				(font
					(size 1 1)
					(thickness 0.15)
				)
			)
		)
		(property "Max. Curr." "22.4A"
			(at 0 0 0)
			(unlocked yes)
			(layer "F.Fab")
			(hide yes)
			(effects
				(font
					(size 1 1)
					(thickness 0.15)
				)
			)
		)
		(property "Author" "Antmicro"
			(at 0 0 0)
			(unlocked yes)
			(layer "F.Fab")
			(hide yes)
			(effects
				(font
					(size 1 1)
					(thickness 0.15)
				)
			)
		)
		(property "License" "Apache-2.0"
			(at 0 0 0)
			(unlocked yes)
			(layer "F.Fab")
			(hide yes)
			(effects
				(font
					(size 1 1)
					(thickness 0.15)
				)
			)
		)
		(property "Tolerance" "template_tolerance"
			(at 0 0 0)
			(unlocked yes)
			(layer "F.Fab")
			(hide yes)
			(effects
				(font
					(size 1 1)
					(thickness 0.15)
				)
			)
		)
		(sheetname "/Power/")
		(sheetfile "power.kicad_sch")
		(attr smd)
		(fp_line
			(start -0.15 -0.4)
			(end 0.15 -0.4)
			(stroke
				(width 0.15)
				(type solid)
			)
			(layer "F.SilkS")
		)
		(fp_line
			(start -0.15 0.4)
			(end 0.15 0.4)
			(stroke
				(width 0.15)
				(type solid)
			)
			(layer "F.SilkS")
		)
		(fp_rect
			(start -1.25 -0.65)
			(end 1.25 0.65)
			(stroke
				(width 0.05)
				(type solid)
			)
			(fill no)
			(layer "F.CrtYd")
		)
		(fp_rect
			(start -0.8 -0.4)
			(end 0.8 0.4)
			(stroke
				(width 0.15)
				(type solid)
			)
			(fill no)
			(layer "F.Fab")
		)
		(pad "1" smd roundrect
			(at -0.7 0)
			(size 0.8 1)
			(layers "F.Cu" "F.Mask" "F.Paste")
			(roundrect_rratio 0.2)
			(net 303 "/Power/+VCCD_OUT")
			(pintype "passive")
		)
		(pad "2" smd roundrect
			(at 0.7 0)
			(size 0.8 1)
			(layers "F.Cu" "F.Mask" "F.Paste")
			(roundrect_rratio 0.2)
			(net 9 "VCCD")
			(pintype "passive")
		)
	)
)
